(kicad_pcb
	(version 20260206)
	(generator "pcbnew")
	(generator_version "10.0")
	(general
		(thickness 1.6)
		(legacy_teardrops no)
	)
	(paper "A4")
	(title_block
		(title "Bryce Canyon_R.DPB_16317-1_OCP.brd")
		(comment 1 "Bryce Canyon / footprints 1303-1304 of 2099")
	)
	(layers
		(0 "F.Cu" signal "TOP")
		(4 "In1.Cu" signal "L2GND")
		(6 "In2.Cu" signal "L3")
		(8 "In3.Cu" signal "L4VCC")
		(10 "In4.Cu" signal "L5VCC")
		(12 "In5.Cu" signal "L6")
		(14 "In6.Cu" signal "L7GND")
		(2 "B.Cu" signal "BOTTOM")
		(9 "F.Adhes" user "F.Adhesive")
		(11 "B.Adhes" user "B.Adhesive")
		(13 "F.Paste" user "Package Geometry/Pastemask Top")
		(15 "B.Paste" user "Package Geometry/Pastemask Bottom")
		(5 "F.SilkS" user "Ref Des/Silkscreen Top")
		(7 "B.SilkS" user "Ref Des/Silkscreen Bottom")
		(1 "F.Mask" user "Board Geometry/Soldermask Top")
		(3 "B.Mask" user "Board Geometry/Soldermask Bottom")
		(17 "Dwgs.User" user "User.Drawings")
		(19 "Cmts.User" user "User.Comments")
		(21 "Eco1.User" user "User.Eco1")
		(23 "Eco2.User" user "User.Eco2")
		(25 "Edge.Cuts" user "Board Geometry/Outline")
		(27 "Margin" user)
		(31 "F.CrtYd" user "Package Geometry/Place Bound Top")
		(29 "B.CrtYd" user "Package Geometry/Place Bound Bottom")
		(35 "F.Fab" user "Ref Des/Assembly Top")
		(33 "B.Fab" user "Ref Des/Assembly Bottom")
	)
	(footprint ""
		(layer "F.Cu")
		(at 460.883 -7.3406 90)
		(property "Reference" "C31"
			(at 0 0 90)
			(layer "F.SilkS")
			(hide yes)
			(effects
				(font
					(size 1.27 1.27)
				)
			)
		)
		(property "Value" "SC1U16V3KX-5GP"
			(at 0 -2.8194 90)
			(unlocked yes)
			(layer "F.Fab")
			(hide yes)
			(effects
				(font
					(size 1.016 1.016)
					(thickness 0.1524)
				)
			)
		)
		(property "Device Type" "C603H36"
			(at 0 -4.3434 90)
			(unlocked yes)
			(layer "F.Fab")
			(hide yes)
			(effects
				(font
					(size 1.016 1.016)
					(thickness 0.1524)
				)
			)
		)
		(duplicate_pad_numbers_are_jumpers no)
		(fp_line
			(start 0.508 0)
			(end -0.508 0)
			(stroke
				(width 0.2032)
				(type default)
			)
			(layer "F.SilkS")
		)
		(fp_rect
			(start -0.5842 1.3335)
			(end 0.5842 -1.3335)
			(stroke
				(width 0)
				(type default)
			)
			(fill no)
			(layer "F.CrtYd")
		)
		(fp_rect
			(start -0.5842 1.3335)
			(end 0.5842 -1.3335)
			(stroke
				(width 0)
				(type default)
			)
			(fill no)
			(layer "F.Fab")
		)
		(pad "1" smd custom
			(at 0 -0.762 90)
			(size 0.2159 0.2159)
			(layers "F.Cu" "F.Mask" "F.Paste")
			(net "P3V3_STBY_B")
			(options
				(clearance outline)
				(anchor circle)
			)
			(primitives
				(gr_poly
					(pts
						(arc
							(start -0.3302 -0.4318)
							(mid -0.402042 -0.402042)
							(end -0.4318 -0.3302)
						)
						(arc
							(start -0.4318 0.3302)
							(mid -0.402042 0.402042)
							(end -0.3302 0.4318)
						)
						(arc
							(start 0.3302 0.4318)
							(mid 0.402042 0.402042)
							(end 0.4318 0.3302)
						)
						(arc
							(start 0.4318 -0.3302)
							(mid 0.402042 -0.402042)
							(end 0.3302 -0.4318)
						)
					)
					(width 0)
					(fill yes)
				)
			)
		)
		(pad "2" smd custom
			(at 0 0.762 90)
			(size 0.2159 0.2159)
			(layers "F.Cu" "F.Mask" "F.Paste")
			(net "GND")
			(options
				(clearance outline)
				(anchor circle)
			)
			(primitives
				(gr_poly
					(pts
						(arc
							(start -0.3302 -0.4318)
							(mid -0.402042 -0.402042)
							(end -0.4318 -0.3302)
						)
						(arc
							(start -0.4318 0.3302)
							(mid -0.402042 0.402042)
							(end -0.3302 0.4318)
						)
						(arc
							(start 0.3302 0.4318)
							(mid 0.402042 0.402042)
							(end 0.4318 0.3302)
						)
						(arc
							(start 0.4318 -0.3302)
							(mid 0.402042 -0.402042)
							(end 0.3302 -0.4318)
						)
					)
					(width 0)
					(fill yes)
				)
			)
		)
	)
	(footprint ""
		(layer "F.Cu")
		(at 458.722476 -221.58325 -90)
		(property "Reference" "R1143"
			(at 0 0 270)
			(layer "F.SilkS")
			(hide yes)
			(effects
				(font
					(size 1.27 1.27)
				)
			)
		)
		(property "Value" "3D01R5F-GP"
			(at 0 -8.9535 270)
			(unlocked yes)
			(layer "F.Fab")
			(hide yes)
			(effects
				(font
					(size 1.27 1.016)
					(thickness 0.1524)
				)
			)
		)
		(property "Device Type" "R805H24"
			(at 0 -10.6299 270)
			(unlocked yes)
			(layer "F.Fab")
			(hide yes)
			(effects
				(font
					(size 1.27 1.016)
					(thickness 0.1524)
				)
			)
		)
		(duplicate_pad_numbers_are_jumpers no)
		(fp_line
			(start -0.889 1.7018)
			(end 0.889 1.7018)
			(stroke
				(width 0.1524)
				(type default)
			)
			(layer "F.SilkS")
		)
		(fp_line
			(start 0.889 1.7018)
			(end 0.889 -0.508)
			(stroke
				(width 0.1524)
				(type default)
			)
			(layer "F.SilkS")
		)
		(fp_line
			(start -0.889 0.0762)
			(end -0.889 1.7018)
			(stroke
				(width 0.1524)
				(type default)
			)
			(layer "F.SilkS")
		)
		(fp_line
			(start -0.889 -1.7018)
			(end -0.889 0.2794)
			(stroke
				(width 0.1524)
				(type default)
			)
			(layer "F.SilkS")
		)
		(fp_line
			(start 0.889 -1.7018)
			(end 0.889 -0.381)
			(stroke
				(width 0.1524)
				(type default)
			)
			(layer "F.SilkS")
		)
		(fp_line
			(start 0.889 -1.7018)
			(end -0.889 -1.7018)
			(stroke
				(width 0.1524)
				(type default)
			)
			(layer "F.SilkS")
		)
		(fp_poly
			(pts
				(xy 0.9652 -1.778) (xy 0.9652 1.778) (xy -0.9652 1.778) (xy -0.9652 -1.778)
			)
			(stroke
				(width 0)
				(type default)
			)
			(fill no)
			(layer "F.CrtYd")
		)
		(fp_rect
			(start -0.9652 1.778)
			(end 0.9652 -1.778)
			(stroke
				(width 0)
				(type default)
			)
			(fill no)
			(layer "F.Fab")
		)
		(pad "1" smd rect
			(at 0 -0.9652 270)
			(size 1.397 1.143)
			(layers "F.Cu" "F.Mask" "F.Paste")
			(net "P5V_B_3_SNB")
		)
		(pad "2" smd rect
			(at 0 0.9652 270)
			(size 1.397 1.143)
			(layers "F.Cu" "F.Mask" "F.Paste")
			(net "GND")
		)
	)
)
